(kicad_pcb
	(version 20260206)
	(generator "pcbnew")
	(generator_version "10.0")
	(general
		(thickness 1.6)
		(legacy_teardrops no)
	)
	(paper "A4")
	(title_block
		(title "01162023_DA0F0TEBIF0_F0T_Expander_BD_F_brd_V02_OCP.brd")
		(comment 1 "Grand Teton / footprints 5708-5708 of 9728")
	)
	(layers
		(0 "F.Cu" signal "TOP")
		(4 "In1.Cu" signal "GND")
		(6 "In2.Cu" signal "VCC")
		(8 "In3.Cu" signal "VCC1")
		(10 "In4.Cu" signal "GND1")
		(12 "In5.Cu" signal "IN1")
		(14 "In6.Cu" signal "GND2")
		(16 "In7.Cu" signal "IN2")
		(18 "In8.Cu" signal "GND3")
		(20 "In9.Cu" signal "IN3")
		(22 "In10.Cu" signal "GND4")
		(24 "In11.Cu" signal "IN4")
		(26 "In12.Cu" signal "GND5")
		(28 "In13.Cu" signal "IN5")
		(30 "In14.Cu" signal "GND6")
		(32 "In15.Cu" signal "IN6")
		(34 "In16.Cu" signal "GND7")
		(2 "B.Cu" signal "BOTTOM")
		(9 "F.Adhes" user "F.Adhesive")
		(11 "B.Adhes" user "B.Adhesive")
		(13 "F.Paste" user "Package Geometry/Pastemask Top")
		(15 "B.Paste" user "Package Geometry/Pastemask Bottom")
		(5 "F.SilkS" user "Ref Des/Silkscreen Top")
		(7 "B.SilkS" user "Ref Des/Silkscreen Bottom")
		(1 "F.Mask" user "Board Geometry/Soldermask Top")
		(3 "B.Mask" user "Board Geometry/Soldermask Bottom")
		(17 "Dwgs.User" user "User.Drawings")
		(19 "Cmts.User" user "User.Comments")
		(21 "Eco1.User" user "User.Eco1")
		(23 "Eco2.User" user "User.Eco2")
		(25 "Edge.Cuts" user "Board Geometry/Outline")
		(27 "Margin" user)
		(31 "F.CrtYd" user "Package Geometry/Place Bound Top")
		(29 "B.CrtYd" user "Package Geometry/Place Bound Bottom")
		(35 "F.Fab" user "Ref Des/Assembly Top")
		(33 "B.Fab" user "Ref Des/Assembly Bottom")
	)
	(footprint ""
		(layer "F.Cu")
		(at 103.7082 -193.7512)
		(property "Reference" "U435"
			(at -4.172458 -9.46658 0)
			(unlocked yes)
			(layer "F.SilkS")
			(effects
				(font
					(size 0.7874 0.5842)
					(thickness 0.1524)
				)
				(justify left)
			)
		)
		(property "Value" ""
			(at 0 0 0)
			(layer "F.Fab")
			(effects
				(font
					(size 1.27 1.27)
				)
			)
		)
		(duplicate_pad_numbers_are_jumpers no)
		(fp_line
			(start -6.1214 0.750062)
			(end -5.1054 0.750062)
			(stroke
				(width 0.1524)
				(type default)
			)
			(layer "F.SilkS")
		)
		(fp_line
			(start -5.08 -1.75006)
			(end -5.588 -1.75006)
			(stroke
				(width 0.1524)
				(type default)
			)
			(layer "F.SilkS")
		)
		(fp_line
			(start -5.08 3.24993)
			(end -5.588 3.24993)
			(stroke
				(width 0.1524)
				(type default)
			)
			(layer "F.SilkS")
		)
		(fp_line
			(start -4.500118 -4.500118)
			(end -4.500118 -4.0386)
			(stroke
				(width 0.1524)
				(type default)
			)
			(layer "F.SilkS")
		)
		(fp_line
			(start -4.500118 4.0386)
			(end -4.500118 4.500118)
			(stroke
				(width 0.1524)
				(type default)
			)
			(layer "F.SilkS")
		)
		(fp_line
			(start -4.500118 4.500118)
			(end -4.0386 4.500118)
			(stroke
				(width 0.1524)
				(type default)
			)
			(layer "F.SilkS")
		)
		(fp_line
			(start -4.0386 -4.500118)
			(end -4.500118 -4.500118)
			(stroke
				(width 0.1524)
				(type default)
			)
			(layer "F.SilkS")
		)
		(fp_line
			(start -2.249932 5.0292)
			(end -2.249932 6.0452)
			(stroke
				(width 0.1524)
				(type default)
			)
			(layer "F.SilkS")
		)
		(fp_line
			(start -1.75006 -6.0706)
			(end -1.75006 -5.0546)
			(stroke
				(width 0.1524)
				(type default)
			)
			(layer "F.SilkS")
		)
		(fp_line
			(start 0.249936 5.0292)
			(end 0.249936 5.5372)
			(stroke
				(width 0.1524)
				(type default)
			)
			(layer "F.SilkS")
		)
		(fp_line
			(start 0.750062 -5.588)
			(end 0.750062 -5.08)
			(stroke
				(width 0.1524)
				(type default)
			)
			(layer "F.SilkS")
		)
		(fp_line
			(start 2.750058 5.0546)
			(end 2.750058 6.0706)
			(stroke
				(width 0.1524)
				(type default)
			)
			(layer "F.SilkS")
		)
		(fp_line
			(start 3.24993 -6.0706)
			(end 3.24993 -5.0546)
			(stroke
				(width 0.1524)
				(type default)
			)
			(layer "F.SilkS")
		)
		(fp_line
			(start 4.0386 4.500118)
			(end 4.500118 4.500118)
			(stroke
				(width 0.1524)
				(type default)
			)
			(layer "F.SilkS")
		)
		(fp_line
			(start 4.500118 -4.500118)
			(end 4.0386 -4.500118)
			(stroke
				(width 0.1524)
				(type default)
			)
			(layer "F.SilkS")
		)
		(fp_line
			(start 4.500118 -4.0386)
			(end 4.500118 -4.500118)
			(stroke
				(width 0.1524)
				(type default)
			)
			(layer "F.SilkS")
		)
		(fp_line
			(start 4.500118 4.500118)
			(end 4.500118 4.0386)
			(stroke
				(width 0.1524)
				(type default)
			)
			(layer "F.SilkS")
		)
		(fp_line
			(start 5.0292 0.249936)
			(end 6.0452 0.249936)
			(stroke
				(width 0.1524)
				(type default)
			)
			(layer "F.SilkS")
		)
		(fp_line
			(start 5.5372 -2.249932)
			(end 5.0292 -2.249932)
			(stroke
				(width 0.1524)
				(type default)
			)
			(layer "F.SilkS")
		)
		(fp_line
			(start 5.5372 2.750058)
			(end 5.0292 2.750058)
			(stroke
				(width 0.1524)
				(type default)
			)
			(layer "F.SilkS")
		)
		(fp_poly
			(pts
				(xy -6.0452 -4.258056) (xy -6.0452 -3.242056) (xy -5.0292 -3.750056)
			)
			(stroke
				(width 0)
				(type default)
			)
			(fill yes)
			(layer "F.SilkS")
		)
		(fp_line
			(start -6.1214 0.750062)
			(end -5.1054 0.750062)
			(stroke
				(width 0.1)
				(type default)
			)
			(layer "F.Fab")
		)
		(fp_line
			(start -5.08 -1.75006)
			(end -5.588 -1.75006)
			(stroke
				(width 0.1)
				(type default)
			)
			(layer "F.Fab")
		)
		(fp_line
			(start -5.08 3.24993)
			(end -5.588 3.24993)
			(stroke
				(width 0.1)
				(type default)
			)
			(layer "F.Fab")
		)
		(fp_line
			(start -4.500118 -4.500118)
			(end -4.500118 4.500118)
			(stroke
				(width 0.1)
				(type default)
			)
			(layer "F.Fab")
		)
		(fp_line
			(start -4.500118 4.500118)
			(end 4.500118 4.500118)
			(stroke
				(width 0.1)
				(type default)
			)
			(layer "F.Fab")
		)
		(fp_line
			(start -2.249932 5.0292)
			(end -2.249932 6.0452)
			(stroke
				(width 0.1)
				(type default)
			)
			(layer "F.Fab")
		)
		(fp_line
			(start -1.75006 -6.0706)
			(end -1.75006 -5.0546)
			(stroke
				(width 0.1)
				(type default)
			)
			(layer "F.Fab")
		)
		(fp_line
			(start 0.249936 5.0292)
			(end 0.249936 5.5372)
			(stroke
				(width 0.1)
				(type default)
			)
			(layer "F.Fab")
		)
		(fp_line
			(start 0.750062 -5.588)
			(end 0.750062 -5.08)
			(stroke
				(width 0.1)
				(type default)
			)
			(layer "F.Fab")
		)
		(fp_line
			(start 2.750058 5.0546)
			(end 2.750058 6.0706)
			(stroke
				(width 0.1)
				(type default)
			)
			(layer "F.Fab")
		)
		(fp_line
			(start 3.24993 -6.0706)
			(end 3.24993 -5.0546)
			(stroke
				(width 0.1)
				(type default)
			)
			(layer "F.Fab")
		)
		(fp_line
			(start 4.500118 -4.500118)
			(end -4.500118 -4.500118)
			(stroke
				(width 0.1)
				(type default)
			)
			(layer "F.Fab")
		)
		(fp_line
			(start 4.500118 4.500118)
			(end 4.500118 -4.500118)
			(stroke
				(width 0.1)
				(type default)
			)
			(layer "F.Fab")
		)
		(fp_line
			(start 5.0292 0.249936)
			(end 6.0452 0.249936)
			(stroke
				(width 0.1)
				(type default)
			)
			(layer "F.Fab")
		)
		(fp_line
			(start 5.5372 -2.249932)
			(end 5.0292 -2.249932)
			(stroke
				(width 0.1)
				(type default)
			)
			(layer "F.Fab")
		)
		(fp_line
			(start 5.5372 2.750058)
			(end 5.0292 2.750058)
			(stroke
				(width 0.1)
				(type default)
			)
			(layer "F.Fab")
		)
		(fp_poly
			(pts
				(xy -6.0452 -4.258056) (xy -6.0452 -3.242056) (xy -5.0292 -3.750056)
			)
			(stroke
				(width 0)
				(type default)
			)
			(fill yes)
			(layer "F.Fab")
		)
		(fp_text user "64"
			(at -5.334 -5.878068 0)
			(unlocked yes)
			(layer "F.SilkS")
			(effects
				(font
					(size 0.7874 0.5842)
					(thickness 0.1524)
				)
			)
		)
		(fp_text user "16"
			(at -5.182616 5.540248 270)
			(unlocked yes)
			(layer "F.SilkS")
			(effects
				(font
					(size 0.7874 0.5842)
					(thickness 0.1524)
				)
			)
		)
		(fp_text user "17"
			(at -3.945128 5.684266 0)
			(unlocked yes)
			(layer "F.SilkS")
			(effects
				(font
					(size 0.7874 0.5842)
					(thickness 0.1524)
				)
			)
		)
		(fp_text user "32"
			(at 4.445 5.496052 0)
			(unlocked yes)
			(layer "F.SilkS")
			(effects
				(font
					(size 0.7874 0.5842)
					(thickness 0.1524)
				)
			)
		)
		(fp_text user "33"
			(at 5.425948 4.318 270)
			(unlocked yes)
			(layer "F.SilkS")
			(effects
				(font
					(size 0.7874 0.5842)
					(thickness 0.1524)
				)
			)
		)
		(fp_text user "49"
			(at 5.761482 -6.223508 0)
			(unlocked yes)
			(layer "F.SilkS")
			(effects
				(font
					(size 0.7874 0.5842)
					(thickness 0.1524)
				)
			)
		)
		(fp_text user "48"
			(at 6.319266 -4.930902 270)
			(unlocked yes)
			(layer "F.SilkS")
			(effects
				(font
					(size 0.7874 0.5842)
					(thickness 0.1524)
				)
			)
		)
		(fp_text user "16"
			(at -5.496052 4.318 270)
			(unlocked yes)
			(layer "F.Fab")
			(effects
				(font
					(size 0.7874 0.5842)
					(thickness 0.1524)
				)
			)
		)
		(fp_text user "64"
			(at -4.572 -5.298948 0)
			(unlocked yes)
			(layer "F.Fab")
			(effects
				(font
					(size 0.7874 0.5842)
					(thickness 0.1524)
				)
			)
		)
		(fp_text user "17"
			(at -4.572 5.496052 0)
			(unlocked yes)
			(layer "F.Fab")
			(effects
				(font
					(size 0.7874 0.5842)
					(thickness 0.1524)
				)
			)
		)
		(fp_text user "49"
			(at 4.445 -5.298948 0)
			(unlocked yes)
			(layer "F.Fab")
			(effects
				(font
					(size 0.7874 0.5842)
					(thickness 0.1524)
				)
			)
		)
		(fp_text user "32"
			(at 4.445 5.496052 0)
			(unlocked yes)
			(layer "F.Fab")
			(effects
				(font
					(size 0.7874 0.5842)
					(thickness 0.1524)
				)
			)
		)
		(fp_text user "48"
			(at 5.425948 -4.445 270)
			(unlocked yes)
			(layer "F.Fab")
			(effects
				(font
					(size 0.7874 0.5842)
					(thickness 0.1524)
				)
			)
		)
		(fp_text user "33"
			(at 5.425948 4.318 270)
			(unlocked yes)
			(layer "F.Fab")
			(effects
				(font
					(size 0.7874 0.5842)
					(thickness 0.1524)
				)
			)
		)
		(pad "1" smd circle
			(at -4.45008 -3.750056 270)
			(size 0 0)
			(layers "F.Cu" "F.Mask" "F.Paste")
			(net "UART_PEX3_CLI_CP2108_TX")
		)
		(pad "2" smd circle
			(at -4.45008 -3.24993 270)
			(size 0 0)
			(layers "F.Cu" "F.Mask" "F.Paste")
			(net "GND")
		)
		(pad "3" smd circle
			(at -4.45008 -2.750058 270)
			(size 0 0)
			(layers "F.Cu" "F.Mask" "F.Paste")
			(net "P3V3_AUX")
		)
		(pad "4" smd circle
			(at -4.45008 -2.249932 270)
			(size 0 0)
			(layers "F.Cu" "F.Mask" "F.Paste")
			(net "UART_PEX3_CLI_CP2108_RX")
		)
		(pad "5" smd circle
			(at -4.45008 -1.75006 270)
			(size 0 0)
			(layers "F.Cu" "F.Mask" "F.Paste")
			(net "Net_9243")
		)
		(pad "6" smd circle
			(at -4.45008 -1.249934 270)
			(size 0 0)
			(layers "F.Cu" "F.Mask" "F.Paste")
			(net "Net_9205")
		)
		(pad "7" smd circle
			(at -4.45008 -0.750062 270)
			(size 0 0)
			(layers "F.Cu" "F.Mask" "F.Paste")
			(net "Net_9209")
		)
		(pad "8" smd circle
			(at -4.45008 -0.249936 270)
			(size 0 0)
			(layers "F.Cu" "F.Mask" "F.Paste")
			(net "Net_9239")
		)
		(pad "9" smd circle
			(at -4.45008 0.249936 270)
			(size 0 0)
			(layers "F.Cu" "F.Mask" "F.Paste")
			(net "Net_9235")
		)
		(pad "10" smd circle
			(at -4.45008 0.750062 270)
			(size 0 0)
			(layers "F.Cu" "F.Mask" "F.Paste")
			(net "Net_9231")
		)
		(pad "11" smd circle
			(at -4.45008 1.249934 270)
			(size 0 0)
			(layers "F.Cu" "F.Mask" "F.Paste")
			(net "Net_9210")
		)
		(pad "12" smd circle
			(at -4.45008 1.75006 270)
			(size 0 0)
			(layers "F.Cu" "F.Mask" "F.Paste")
			(net "Net_9240")
		)
		(pad "13" smd circle
			(at -4.45008 2.249932 270)
			(size 0 0)
			(layers "F.Cu" "F.Mask" "F.Paste")
			(net "Net_9244")
		)
		(pad "14" smd circle
			(at -4.45008 2.750058 270)
			(size 0 0)
			(layers "F.Cu" "F.Mask" "F.Paste")
			(net "Net_9206")
		)
		(pad "15" smd circle
			(at -4.45008 3.24993 270)
			(size 0 0)
			(layers "F.Cu" "F.Mask" "F.Paste")
			(net "UART_PEX2_CLI_CP2108_TX")
		)
		(pad "16" smd circle
			(at -4.45008 3.750056 270)
			(size 0 0)
			(layers "F.Cu" "F.Mask" "F.Paste")
			(net "UART_PEX2_CLI_CP2108_RX")
		)
		(pad "17" smd circle
			(at -3.750056 4.45008)
			(size 0 0)
			(layers "F.Cu" "F.Mask" "F.Paste")
			(net "Net_9236")
		)
		(pad "18" smd circle
			(at -3.24993 4.45008)
			(size 0 0)
			(layers "F.Cu" "F.Mask" "F.Paste")
			(net "Net_9232")
		)
		(pad "19" smd circle
			(at -2.750058 4.45008)
			(size 0 0)
			(layers "F.Cu" "F.Mask" "F.Paste")
			(net "Net_9203")
		)
		(pad "20" smd circle
			(at -2.249932 4.45008)
			(size 0 0)
			(layers "F.Cu" "F.Mask" "F.Paste")
			(net "Net_9204")
		)
		(pad "21" smd circle
			(at -1.75006 4.45008)
			(size 0 0)
			(layers "F.Cu" "F.Mask" "F.Paste")
			(net "Net_9223")
		)
		(pad "22" smd circle
			(at -1.249934 4.45008)
			(size 0 0)
			(layers "F.Cu" "F.Mask" "F.Paste")
			(net "Net_9224")
		)
		(pad "23" smd circle
			(at -0.750062 4.45008)
			(size 0 0)
			(layers "F.Cu" "F.Mask" "F.Paste")
			(net "Net_9225")
		)
		(pad "24" smd circle
			(at -0.249936 4.45008)
			(size 0 0)
			(layers "F.Cu" "F.Mask" "F.Paste")
			(net "P3V3_AUX")
		)
		(pad "25" smd circle
			(at 0.249936 4.45008)
			(size 0 0)
			(layers "F.Cu" "F.Mask" "F.Paste")
			(net "GND")
		)
		(pad "26" smd circle
			(at 0.750062 4.45008)
			(size 0 0)
			(layers "F.Cu" "F.Mask" "F.Paste")
			(net "Net_9226")
		)
		(pad "27" smd circle
			(at 1.249934 4.45008)
			(size 0 0)
			(layers "F.Cu" "F.Mask" "F.Paste")
			(net "Net_9227")
		)
		(pad "28" smd circle
			(at 1.75006 4.45008)
			(size 0 0)
			(layers "F.Cu" "F.Mask" "F.Paste")
			(net "Net_9228")
		)
		(pad "29" smd circle
			(at 2.249932 4.45008)
			(size 0 0)
			(layers "F.Cu" "F.Mask" "F.Paste")
			(net "Net_9215")
		)
		(pad "30" smd circle
			(at 2.750058 4.45008)
			(size 0 0)
			(layers "F.Cu" "F.Mask" "F.Paste")
			(net "Net_9216")
		)
		(pad "31" smd circle
			(at 3.24993 4.45008)
			(size 0 0)
			(layers "F.Cu" "F.Mask" "F.Paste")
			(net "Net_9217")
		)
		(pad "32" smd circle
			(at 3.750056 4.45008)
			(size 0 0)
			(layers "F.Cu" "F.Mask" "F.Paste")
			(net "Net_9218")
		)
		(pad "33" smd circle
			(at 4.45008 3.750056 90)
			(size 0 0)
			(layers "F.Cu" "F.Mask" "F.Paste")
			(net "Net_9219")
		)
		(pad "34" smd circle
			(at 4.45008 3.24993 90)
			(size 0 0)
			(layers "F.Cu" "F.Mask" "F.Paste")
			(net "Net_9220")
		)
		(pad "35" smd circle
			(at 4.45008 2.750058 90)
			(size 0 0)
			(layers "F.Cu" "F.Mask" "F.Paste")
			(net "Net_9214")
		)
		(pad "36" smd circle
			(at 4.45008 2.249932 90)
			(size 0 0)
			(layers "F.Cu" "F.Mask" "F.Paste")
			(net "Net_9213")
		)
		(pad "37" smd circle
			(at 4.45008 1.75006 90)
			(size 0 0)
			(layers "F.Cu" "F.Mask" "F.Paste")
			(net "Net_9221")
		)
		(pad "38" smd circle
			(at 4.45008 1.249934 90)
			(size 0 0)
			(layers "F.Cu" "F.Mask" "F.Paste")
			(net "Net_9222")
		)
		(pad "39" smd circle
			(at 4.45008 0.750062 90)
			(size 0 0)
			(layers "F.Cu" "F.Mask" "F.Paste")
			(net "P3V3_AUX")
		)
		(pad "40" smd circle
			(at 4.45008 0.249936 90)
			(size 0 0)
			(layers "F.Cu" "F.Mask" "F.Paste")
			(net "Net_9229")
		)
		(pad "41" smd circle
			(at 4.45008 -0.249936 90)
			(size 0 0)
			(layers "F.Cu" "F.Mask" "F.Paste")
			(net "Net_9230")
		)
		(pad "42" smd circle
			(at 4.45008 -0.750062 90)
			(size 0 0)
			(layers "F.Cu" "F.Mask" "F.Paste")
			(net "Net_9211")
		)
		(pad "43" smd circle
			(at 4.45008 -1.249934 90)
			(size 0 0)
			(layers "F.Cu" "F.Mask" "F.Paste")
			(net "Net_9241")
		)
		(pad "44" smd circle
			(at 4.45008 -1.75006 90)
			(size 0 0)
			(layers "F.Cu" "F.Mask" "F.Paste")
			(net "Net_9237")
		)
		(pad "45" smd circle
			(at 4.45008 -2.249932 90)
			(size 0 0)
			(layers "F.Cu" "F.Mask" "F.Paste")
			(net "Net_9233")
		)
		(pad "46" smd circle
			(at 4.45008 -2.750058 90)
			(size 0 0)
			(layers "F.Cu" "F.Mask" "F.Paste")
			(net "Net_9245")
		)
		(pad "47" smd circle
			(at 4.45008 -3.24993 90)
			(size 0 0)
			(layers "F.Cu" "F.Mask" "F.Paste")
			(net "Net_9207")
		)
		(pad "48" smd circle
			(at 4.45008 -3.750056 90)
			(size 0 0)
			(layers "F.Cu" "F.Mask" "F.Paste")
			(net "UART_PEX1_CLI_CP2108_TX")
		)
		(pad "49" smd circle
			(at 3.750056 -4.45008 180)
			(size 0 0)
			(layers "F.Cu" "F.Mask" "F.Paste")
			(net "UART_PEX1_CLI_CP2108_RX")
		)
		(pad "50" smd circle
			(at 3.24993 -4.45008 180)
			(size 0 0)
			(layers "F.Cu" "F.Mask" "F.Paste")
			(net "Net_9212")
		)
		(pad "51" smd circle
			(at 2.750058 -4.45008 180)
			(size 0 0)
			(layers "F.Cu" "F.Mask" "F.Paste")
			(net "Net_9242")
		)
		(pad "52" smd circle
			(at 2.249932 -4.45008 180)
			(size 0 0)
			(layers "F.Cu" "F.Mask" "F.Paste")
			(net "Net_9238")
		)
		(pad "53" smd circle
			(at 1.75006 -4.45008 180)
			(size 0 0)
			(layers "F.Cu" "F.Mask" "F.Paste")
			(net "Net_9234")
		)
		(pad "54" smd circle
			(at 1.249934 -4.45008 180)
			(size 0 0)
			(layers "F.Cu" "F.Mask" "F.Paste")
			(net "Net_9246")
		)
		(pad "55" smd circle
			(at 0.750062 -4.45008 180)
			(size 0 0)
			(layers "F.Cu" "F.Mask" "F.Paste")
			(net "Net_9208")
		)
		(pad "56" smd circle
			(at 0.249936 -4.45008 180)
			(size 0 0)
			(layers "F.Cu" "F.Mask" "F.Paste")
			(net "UART_PEX0_CLI_CP2108_TX")
		)
		(pad "57" smd circle
			(at -0.249936 -4.45008 180)
			(size 0 0)
			(layers "F.Cu" "F.Mask" "F.Paste")
			(net "UART_PEX0_CLI_CP2108_RX")
		)
		(pad "58" smd circle
			(at -0.750062 -4.45008 180)
			(size 0 0)
			(layers "F.Cu" "F.Mask" "F.Paste")
			(net "P3V3_AUX")
		)
		(pad "59" smd circle
			(at -1.249934 -4.45008 180)
			(size 0 0)
			(layers "F.Cu" "F.Mask" "F.Paste")
			(net "GND")
		)
		(pad "60" smd circle
			(at -1.75006 -4.45008 180)
			(size 0 0)
			(layers "F.Cu" "F.Mask" "F.Paste")
			(net "P3V3_AUX")
		)
		(pad "61" smd circle
			(at -2.249932 -4.45008 180)
			(size 0 0)
			(layers "F.Cu" "F.Mask" "F.Paste")
			(net "P3V3_AUX")
		)
		(pad "62" smd circle
			(at -2.750058 -4.45008 180)
			(size 0 0)
			(layers "F.Cu" "F.Mask" "F.Paste")
			(net "USB2_CP2108_CLI_DP")
		)
		(pad "63" smd circle
			(at -3.24993 -4.45008 180)
			(size 0 0)
			(layers "F.Cu" "F.Mask" "F.Paste")
			(net "USB2_CP2108_CLI_DN")
		)
		(pad "64" smd circle
			(at -3.750056 -4.45008 180)
			(size 0 0)
			(layers "F.Cu" "F.Mask" "F.Paste")
			(net "RST_CP2108_CLI_R_N")
		)
		(pad "TH" smd rect
			(at 0 0)
			(size 4.2672 4.2672)
			(layers "F.Cu" "F.Mask" "F.Paste")
			(net "GND")
		)
		(zone
			(layer "F.Cu")
			(hatch none 0.5)
			(connect_pads
				(clearance 0)
			)
			(min_thickness 0.25)
			(keepout
				(tracks not_allowed)
				(vias allowed)
				(pads allowed)
				(copperpour not_allowed)
				(footprints allowed)
			)
			(placement
				(enabled no)
				(sheetname "")
			)
			(fill
				(thermal_gap 0.5)
				(thermal_bridge_width 0.5)
				(island_removal_mode 0)
			)
			(polygon
				(pts
					(xy 99.7458 -194.5132) (xy 99.7458 -189.7888) (xy 107.6706 -189.7888) (xy 107.6706 -197.7136) (xy 99.7458 -197.7136)
					(xy 99.7458 -194.5386) (xy 101.5238 -194.5386) (xy 101.5238 -195.9356) (xy 105.8926 -195.9356)
					(xy 105.8926 -191.5668) (xy 101.5238 -191.5668) (xy 101.5238 -194.5132)
				)
			)
		)
	)
)
